# T6G (Grand Teton) — schematic netlist excerpt (pin names and nets, part order shuffled) for the footprints in the layout excerpt that follows; sources: Cadence DE-HDL packaged netlist, KiCad conversion of 04192023_DAF0TMB3IC0_F0TG_MB_C_brd_V02_OCP.brd

PC498  Q_CAPP  220UF 4V 20% SPCAP  pkg SMLF  page 194 : A = PVDDCR_CPU0_P0 ; B = GND
PR305  Q_RES  0 5% CHIP  pkg 0402LF  page 193 : A = SVID_PVDDCR_CPU0_P0_SVTI ; B = SVID_PVDDCR_CPU0_P0_SVTI_R

(kicad_pcb
	(version 20260206)
	(generator "pcbnew")
	(generator_version "10.0")
	(general
		(thickness 1.6)
		(legacy_teardrops no)
	)
	(paper "A4")
	(title_block
		(title "04192023_DAF0TMB3IC0_F0TG_MB_C_brd_V02_OCP.brd")
		(comment 1 "Grand Teton / footprints 6200-6201 of 8354")
	)
	(layers
		(0 "F.Cu" signal "TOP")
		(4 "In1.Cu" signal "GND")
		(6 "In2.Cu" signal "IN1")
		(8 "In3.Cu" signal "GND1")
		(10 "In4.Cu" signal "IN2")
		(12 "In5.Cu" signal "GND2")
		(14 "In6.Cu" signal "IN3")
		(16 "In7.Cu" signal "GND3")
		(18 "In8.Cu" signal "VCC")
		(20 "In9.Cu" signal "VCC1")
		(22 "In10.Cu" signal "GND4")
		(24 "In11.Cu" signal "IN4")
		(26 "In12.Cu" signal "GND5")
		(28 "In13.Cu" signal "IN5")
		(30 "In14.Cu" signal "GND6")
		(32 "In15.Cu" signal "IN6")
		(34 "In16.Cu" signal "GND7")
		(2 "B.Cu" signal "BOTTOM")
		(9 "F.Adhes" user "F.Adhesive")
		(11 "B.Adhes" user "B.Adhesive")
		(13 "F.Paste" user "Package Geometry/Pastemask Top")
		(15 "B.Paste" user "Package Geometry/Pastemask Bottom")
		(5 "F.SilkS" user "Ref Des/Silkscreen Top")
		(7 "B.SilkS" user "Ref Des/Silkscreen Bottom")
		(1 "F.Mask" user "Board Geometry/Soldermask Top")
		(3 "B.Mask" user "Board Geometry/Soldermask Bottom")
		(17 "Dwgs.User" user "User.Drawings")
		(19 "Cmts.User" user "User.Comments")
		(21 "Eco1.User" user "User.Eco1")
		(23 "Eco2.User" user "User.Eco2")
		(25 "Edge.Cuts" user "Board Geometry/Outline")
		(27 "Margin" user)
		(31 "F.CrtYd" user "Package Geometry/Place Bound Top")
		(29 "B.CrtYd" user "Package Geometry/Place Bound Bottom")
		(35 "F.Fab" user "Ref Des/Assembly Top")
		(33 "B.Fab" user "Ref Des/Assembly Bottom")
	)
	(footprint ""
		(layer "B.Cu")
		(at 372.818406 -189.50432 90)
		(property "Reference" "PC498"
			(at 6.582664 -0.550926 270)
			(unlocked yes)
			(layer "B.SilkS")
			(effects
				(font
					(size 0.7874 0.5842)
					(thickness 0.1524)
				)
				(justify left mirror)
			)
		)
		(property "Value" ""
			(at 0 0 90)
			(layer "B.Fab")
			(effects
				(font
					(size 1.27 1.27)
				)
				(justify mirror)
			)
		)
		(duplicate_pad_numbers_are_jumpers no)
		(fp_line
			(start 4.533392 -2.249932)
			(end -4.533392 -2.249932)
			(stroke
				(width 0.1524)
				(type default)
			)
			(layer "B.SilkS")
		)
		(fp_line
			(start -4.533392 -2.249932)
			(end -4.533392 2.249932)
			(stroke
				(width 0.1524)
				(type default)
			)
			(layer "B.SilkS")
		)
		(fp_line
			(start 4.533392 2.249932)
			(end 4.533392 -2.249932)
			(stroke
				(width 0.1524)
				(type default)
			)
			(layer "B.SilkS")
		)
		(fp_line
			(start -4.533392 2.249932)
			(end 4.533392 2.249932)
			(stroke
				(width 0.1524)
				(type default)
			)
			(layer "B.SilkS")
		)
		(fp_rect
			(start 4.533392 -2.326132)
			(end 5.39242 2.326132)
			(stroke
				(width 0)
				(type default)
			)
			(fill yes)
			(layer "B.SilkS")
		)
		(fp_line
			(start 3.750056 -2.249932)
			(end -3.750056 -2.249932)
			(stroke
				(width 0.1)
				(type default)
			)
			(layer "B.Fab")
		)
		(fp_line
			(start -3.750056 -2.249932)
			(end -3.750056 2.249932)
			(stroke
				(width 0.1)
				(type default)
			)
			(layer "B.Fab")
		)
		(fp_line
			(start 3.750056 2.249932)
			(end 3.750056 -2.249932)
			(stroke
				(width 0.1)
				(type default)
			)
			(layer "B.Fab")
		)
		(fp_line
			(start -3.750056 2.249932)
			(end 3.750056 2.249932)
			(stroke
				(width 0.1)
				(type default)
			)
			(layer "B.Fab")
		)
		(fp_text user "-"
			(at -4.8514 -0.14605 90)
			(unlocked yes)
			(layer "B.SilkS")
			(effects
				(font
					(size 1.905 1.4224)
					(thickness 0.1524)
				)
				(justify left mirror)
			)
		)
		(fp_text user "+"
			(at 6.322314 0.786384 0)
			(unlocked yes)
			(layer "B.SilkS")
			(effects
				(font
					(size 1.905 1.4224)
					(thickness 0.1524)
				)
				(justify left mirror)
			)
		)
		(fp_text user "-"
			(at -4.8514 -0.14605 90)
			(unlocked yes)
			(layer "B.Fab")
			(effects
				(font
					(size 1.905 1.4224)
					(thickness 0.1524)
				)
				(justify left mirror)
			)
		)
		(fp_text user "+"
			(at 6.322314 0.786384 0)
			(unlocked yes)
			(layer "B.Fab")
			(effects
				(font
					(size 1.905 1.4224)
					(thickness 0.1524)
				)
				(justify left mirror)
			)
		)
		(pad "1" smd rect
			(at 3.199892 0 270)
			(size 2.413 2.8194)
			(layers "B.Cu" "B.Mask" "B.Paste")
			(net "PVDDCR_CPU0_P0")
		)
		(pad "2" smd rect
			(at -3.199892 0 270)
			(size 2.413 2.8194)
			(layers "B.Cu" "B.Mask" "B.Paste")
			(net "GND")
		)
	)
	(footprint ""
		(layer "B.Cu")
		(at 372.937278 -147.568158 180)
		(property "Reference" "PR305"
			(at 0 0 0)
			(layer "B.SilkS")
			(hide yes)
			(effects
				(font
					(size 1.27 1.27)
				)
				(justify mirror)
			)
		)
		(property "Value" ""
			(at 0 0 0)
			(layer "B.Fab")
			(effects
				(font
					(size 1.27 1.27)
				)
				(justify mirror)
			)
		)
		(duplicate_pad_numbers_are_jumpers no)
		(fp_line
			(start 0.7874 0.4064)
			(end 0.7874 -0.4064)
			(stroke
				(width 0.1524)
				(type default)
			)
			(layer "B.SilkS")
		)
		(fp_line
			(start 0.7874 -0.4064)
			(end -0.7874 -0.4064)
			(stroke
				(width 0.1524)
				(type default)
			)
			(layer "B.SilkS")
		)
		(fp_line
			(start -0.7874 0.4064)
			(end 0.7874 0.4064)
			(stroke
				(width 0.1524)
				(type default)
			)
			(layer "B.SilkS")
		)
		(fp_line
			(start -0.7874 -0.4064)
			(end -0.7874 0.4064)
			(stroke
				(width 0.1524)
				(type default)
			)
			(layer "B.SilkS")
		)
		(fp_line
			(start 0.67945 0.3048)
			(end 0.67945 -0.305054)
			(stroke
				(width 0.1)
				(type default)
			)
			(layer "B.Fab")
		)
		(fp_line
			(start 0.67945 -0.305054)
			(end 0.12065 -0.305054)
			(stroke
				(width 0.1)
				(type default)
			)
			(layer "B.Fab")
		)
		(fp_line
			(start 0.12065 0.3048)
			(end 0.67945 0.3048)
			(stroke
				(width 0.1)
				(type default)
			)
			(layer "B.Fab")
		)
		(fp_line
			(start 0.12065 0.2794)
			(end 0.12065 0.3048)
			(stroke
				(width 0.1)
				(type default)
			)
			(layer "B.Fab")
		)
		(fp_line
			(start 0.12065 -0.2794)
			(end -0.12065 -0.2794)
			(stroke
				(width 0.1)
				(type default)
			)
			(layer "B.Fab")
		)
		(fp_line
			(start 0.12065 -0.305054)
			(end 0.12065 -0.2794)
			(stroke
				(width 0.1)
				(type default)
			)
			(layer "B.Fab")
		)
		(fp_line
			(start -0.120396 0.3048)
			(end -0.120396 0.2794)
			(stroke
				(width 0.1)
				(type default)
			)
			(layer "B.Fab")
		)
		(fp_line
			(start -0.120396 0.2794)
			(end 0.12065 0.2794)
			(stroke
				(width 0.1)
				(type default)
			)
			(layer "B.Fab")
		)
		(fp_line
			(start -0.12065 -0.2794)
			(end -0.12065 -0.3048)
			(stroke
				(width 0.1)
				(type default)
			)
			(layer "B.Fab")
		)
		(fp_line
			(start -0.12065 -0.3048)
			(end -0.67945 -0.3048)
			(stroke
				(width 0.1)
				(type default)
			)
			(layer "B.Fab")
		)
		(fp_line
			(start -0.67945 0.3048)
			(end -0.120396 0.3048)
			(stroke
				(width 0.1)
				(type default)
			)
			(layer "B.Fab")
		)
		(fp_line
			(start -0.67945 -0.3048)
			(end -0.67945 0.3048)
			(stroke
				(width 0.1)
				(type default)
			)
			(layer "B.Fab")
		)
		(pad "1" smd circle
			(at 0.40005 0)
			(size 0 0)
			(layers "B.Cu" "B.Mask" "B.Paste")
			(net "SVID_PVDDCR_CPU0_P0_SVTI")
		)
		(pad "2" smd circle
			(at -0.40005 0)
			(size 0 0)
			(layers "B.Cu" "B.Mask" "B.Paste")
			(net "SVID_PVDDCR_CPU0_P0_SVTI_R")
		)
	)
)
